# T6G (Grand Teton) — schematic netlist excerpt (pin names and nets, part order shuffled) for the footprints in the layout excerpt that follows; sources: Cadence DE-HDL packaged netlist, KiCad conversion of 04192023_DAF0TMB3IC0_F0TG_MB_C_brd_V02_OCP.brd

C2407  Q_CAP  22UF 4V 20% X6S  pkg C0402  page 74 : A = PVDDCR_SOC_P1 ; B = GND
PR604  Q_RES  4.99K 1% EMPTY  pkg 0402LF  page 224 : A = PVDD11_S3_P1_VINSEN ; B = GND

(kicad_pcb
	(version 20260206)
	(generator "pcbnew")
	(generator_version "10.0")
	(general
		(thickness 1.6)
		(legacy_teardrops no)
	)
	(paper "A4")
	(title_block
		(title "04192023_DAF0TMB3IC0_F0TG_MB_C_brd_V02_OCP.brd")
		(comment 1 "Grand Teton / footprints 7150-7151 of 8354")
	)
	(layers
		(0 "F.Cu" signal "TOP")
		(4 "In1.Cu" signal "GND")
		(6 "In2.Cu" signal "IN1")
		(8 "In3.Cu" signal "GND1")
		(10 "In4.Cu" signal "IN2")
		(12 "In5.Cu" signal "GND2")
		(14 "In6.Cu" signal "IN3")
		(16 "In7.Cu" signal "GND3")
		(18 "In8.Cu" signal "VCC")
		(20 "In9.Cu" signal "VCC1")
		(22 "In10.Cu" signal "GND4")
		(24 "In11.Cu" signal "IN4")
		(26 "In12.Cu" signal "GND5")
		(28 "In13.Cu" signal "IN5")
		(30 "In14.Cu" signal "GND6")
		(32 "In15.Cu" signal "IN6")
		(34 "In16.Cu" signal "GND7")
		(2 "B.Cu" signal "BOTTOM")
		(9 "F.Adhes" user "F.Adhesive")
		(11 "B.Adhes" user "B.Adhesive")
		(13 "F.Paste" user "Package Geometry/Pastemask Top")
		(15 "B.Paste" user "Package Geometry/Pastemask Bottom")
		(5 "F.SilkS" user "Ref Des/Silkscreen Top")
		(7 "B.SilkS" user "Ref Des/Silkscreen Bottom")
		(1 "F.Mask" user "Board Geometry/Soldermask Top")
		(3 "B.Mask" user "Board Geometry/Soldermask Bottom")
		(17 "Dwgs.User" user "User.Drawings")
		(19 "Cmts.User" user "User.Comments")
		(21 "Eco1.User" user "User.Eco1")
		(23 "Eco2.User" user "User.Eco2")
		(25 "Edge.Cuts" user "Board Geometry/Outline")
		(27 "Margin" user)
		(31 "F.CrtYd" user "Package Geometry/Place Bound Top")
		(29 "B.CrtYd" user "Package Geometry/Place Bound Bottom")
		(35 "F.Fab" user "Ref Des/Assembly Top")
		(33 "B.Fab" user "Ref Des/Assembly Bottom")
	)
	(footprint ""
		(layer "B.Cu")
		(at 164.325554 -350.762062)
		(property "Reference" "PR604"
			(at 0 0 0)
			(layer "B.SilkS")
			(hide yes)
			(effects
				(font
					(size 1.27 1.27)
				)
				(justify mirror)
			)
		)
		(property "Value" ""
			(at 0 0 0)
			(layer "B.Fab")
			(effects
				(font
					(size 1.27 1.27)
				)
				(justify mirror)
			)
		)
		(duplicate_pad_numbers_are_jumpers no)
		(fp_line
			(start -0.7874 -0.4064)
			(end -0.7874 0.4064)
			(stroke
				(width 0.1524)
				(type default)
			)
			(layer "B.SilkS")
		)
		(fp_line
			(start -0.7874 0.4064)
			(end 0.7874 0.4064)
			(stroke
				(width 0.1524)
				(type default)
			)
			(layer "B.SilkS")
		)
		(fp_line
			(start 0.7874 -0.4064)
			(end -0.7874 -0.4064)
			(stroke
				(width 0.1524)
				(type default)
			)
			(layer "B.SilkS")
		)
		(fp_line
			(start 0.7874 0.4064)
			(end 0.7874 -0.4064)
			(stroke
				(width 0.1524)
				(type default)
			)
			(layer "B.SilkS")
		)
		(fp_line
			(start -0.67945 -0.3048)
			(end -0.67945 0.3048)
			(stroke
				(width 0.1)
				(type default)
			)
			(layer "B.Fab")
		)
		(fp_line
			(start -0.67945 0.3048)
			(end -0.120396 0.3048)
			(stroke
				(width 0.1)
				(type default)
			)
			(layer "B.Fab")
		)
		(fp_line
			(start -0.12065 -0.3048)
			(end -0.67945 -0.3048)
			(stroke
				(width 0.1)
				(type default)
			)
			(layer "B.Fab")
		)
		(fp_line
			(start -0.12065 -0.2794)
			(end -0.12065 -0.3048)
			(stroke
				(width 0.1)
				(type default)
			)
			(layer "B.Fab")
		)
		(fp_line
			(start -0.120396 0.2794)
			(end 0.12065 0.2794)
			(stroke
				(width 0.1)
				(type default)
			)
			(layer "B.Fab")
		)
		(fp_line
			(start -0.120396 0.3048)
			(end -0.120396 0.2794)
			(stroke
				(width 0.1)
				(type default)
			)
			(layer "B.Fab")
		)
		(fp_line
			(start 0.12065 -0.305054)
			(end 0.12065 -0.2794)
			(stroke
				(width 0.1)
				(type default)
			)
			(layer "B.Fab")
		)
		(fp_line
			(start 0.12065 -0.2794)
			(end -0.12065 -0.2794)
			(stroke
				(width 0.1)
				(type default)
			)
			(layer "B.Fab")
		)
		(fp_line
			(start 0.12065 0.2794)
			(end 0.12065 0.3048)
			(stroke
				(width 0.1)
				(type default)
			)
			(layer "B.Fab")
		)
		(fp_line
			(start 0.12065 0.3048)
			(end 0.67945 0.3048)
			(stroke
				(width 0.1)
				(type default)
			)
			(layer "B.Fab")
		)
		(fp_line
			(start 0.67945 -0.305054)
			(end 0.12065 -0.305054)
			(stroke
				(width 0.1)
				(type default)
			)
			(layer "B.Fab")
		)
		(fp_line
			(start 0.67945 0.3048)
			(end 0.67945 -0.305054)
			(stroke
				(width 0.1)
				(type default)
			)
			(layer "B.Fab")
		)
		(pad "1" smd circle
			(at 0.40005 0 180)
			(size 0 0)
			(layers "B.Cu" "B.Mask" "B.Paste")
			(net "PVDD11_S3_P1_VINSEN")
		)
		(pad "2" smd circle
			(at -0.40005 0 180)
			(size 0 0)
			(layers "B.Cu" "B.Mask" "B.Paste")
			(net "GND")
		)
	)
	(footprint ""
		(layer "B.Cu")
		(at 115.70589 -257.74523 180)
		(property "Reference" "C2407"
			(at 0 0 0)
			(layer "B.SilkS")
			(hide yes)
			(effects
				(font
					(size 1.27 1.27)
				)
				(justify mirror)
			)
		)
		(property "Value" ""
			(at 0 0 0)
			(layer "B.Fab")
			(effects
				(font
					(size 1.27 1.27)
				)
				(justify mirror)
			)
		)
		(duplicate_pad_numbers_are_jumpers no)
		(fp_line
			(start 0.7874 0.4064)
			(end 0.7874 -0.4064)
			(stroke
				(width 0.1524)
				(type default)
			)
			(layer "B.SilkS")
		)
		(fp_line
			(start 0.7874 -0.4064)
			(end -0.7874 -0.4064)
			(stroke
				(width 0.1524)
				(type default)
			)
			(layer "B.SilkS")
		)
		(fp_line
			(start -0.7874 0.4064)
			(end 0.7874 0.4064)
			(stroke
				(width 0.1524)
				(type default)
			)
			(layer "B.SilkS")
		)
		(fp_line
			(start -0.7874 -0.4064)
			(end -0.7874 0.4064)
			(stroke
				(width 0.1524)
				(type default)
			)
			(layer "B.SilkS")
		)
		(fp_line
			(start 0.67945 0.3048)
			(end 0.67945 -0.305054)
			(stroke
				(width 0.1)
				(type default)
			)
			(layer "B.Fab")
		)
		(fp_line
			(start 0.67945 -0.305054)
			(end 0.12065 -0.305054)
			(stroke
				(width 0.1)
				(type default)
			)
			(layer "B.Fab")
		)
		(fp_line
			(start 0.12065 0.3048)
			(end 0.67945 0.3048)
			(stroke
				(width 0.1)
				(type default)
			)
			(layer "B.Fab")
		)
		(fp_line
			(start 0.12065 0.2794)
			(end 0.12065 0.3048)
			(stroke
				(width 0.1)
				(type default)
			)
			(layer "B.Fab")
		)
		(fp_line
			(start 0.12065 -0.2794)
			(end -0.12065 -0.2794)
			(stroke
				(width 0.1)
				(type default)
			)
			(layer "B.Fab")
		)
		(fp_line
			(start 0.12065 -0.305054)
			(end 0.12065 -0.2794)
			(stroke
				(width 0.1)
				(type default)
			)
			(layer "B.Fab")
		)
		(fp_line
			(start -0.120396 0.3048)
			(end -0.120396 0.2794)
			(stroke
				(width 0.1)
				(type default)
			)
			(layer "B.Fab")
		)
		(fp_line
			(start -0.120396 0.2794)
			(end 0.12065 0.2794)
			(stroke
				(width 0.1)
				(type default)
			)
			(layer "B.Fab")
		)
		(fp_line
			(start -0.12065 -0.2794)
			(end -0.12065 -0.3048)
			(stroke
				(width 0.1)
				(type default)
			)
			(layer "B.Fab")
		)
		(fp_line
			(start -0.12065 -0.3048)
			(end -0.67945 -0.3048)
			(stroke
				(width 0.1)
				(type default)
			)
			(layer "B.Fab")
		)
		(fp_line
			(start -0.67945 0.3048)
			(end -0.120396 0.3048)
			(stroke
				(width 0.1)
				(type default)
			)
			(layer "B.Fab")
		)
		(fp_line
			(start -0.67945 -0.3048)
			(end -0.67945 0.3048)
			(stroke
				(width 0.1)
				(type default)
			)
			(layer "B.Fab")
		)
		(pad "1" smd circle
			(at 0.40005 0)
			(size 0 0)
			(layers "B.Cu" "B.Mask" "B.Paste")
			(net "PVDDCR_SOC_P1")
		)
		(pad "2" smd circle
			(at -0.40005 0)
			(size 0 0)
			(layers "B.Cu" "B.Mask" "B.Paste")
			(net "GND")
		)
	)
)
